(kicad_pcb
	(version 20260206)
	(generator "pcbnew")
	(generator_version "10.0")
	(general
		(thickness 1.6)
		(legacy_teardrops no)
	)
	(paper "A4")
	(title_block
		(title "Wiwynn_Tioga_Pass_MB.brd")
		(comment 1 "Tioga Pass / footprints 1268-1273 of 4770")
	)
	(layers
		(0 "F.Cu" signal "TOP")
		(4 "In1.Cu" signal "L2GND")
		(6 "In2.Cu" signal "L3")
		(8 "In3.Cu" signal "L4GND")
		(10 "In4.Cu" signal "L5")
		(12 "In5.Cu" signal "L6GND")
		(14 "In6.Cu" signal "L7VCC")
		(16 "In7.Cu" signal "L8VCC")
		(18 "In8.Cu" signal "L9GND")
		(20 "In9.Cu" signal "L10")
		(22 "In10.Cu" signal "L11GND")
		(24 "In11.Cu" signal "L12")
		(26 "In12.Cu" signal "L13GND")
		(2 "B.Cu" signal "BOTTOM")
		(9 "F.Adhes" user "F.Adhesive")
		(11 "B.Adhes" user "B.Adhesive")
		(13 "F.Paste" user "Package Geometry/Pastemask Top")
		(15 "B.Paste" user "Package Geometry/Pastemask Bottom")
		(5 "F.SilkS" user "Ref Des/Silkscreen Top")
		(7 "B.SilkS" user "Ref Des/Silkscreen Bottom")
		(1 "F.Mask" user "Board Geometry/Soldermask Top")
		(3 "B.Mask" user "Board Geometry/Soldermask Bottom")
		(17 "Dwgs.User" user "User.Drawings")
		(19 "Cmts.User" user "User.Comments")
		(21 "Eco1.User" user "User.Eco1")
		(23 "Eco2.User" user "User.Eco2")
		(25 "Edge.Cuts" user "Board Geometry/Outline")
		(27 "Margin" user)
		(31 "F.CrtYd" user "Package Geometry/Place Bound Top")
		(29 "B.CrtYd" user "Package Geometry/Place Bound Bottom")
		(35 "F.Fab" user "Ref Des/Assembly Top")
		(33 "B.Fab" user "Ref Des/Assembly Bottom")
	)
	(footprint ""
		(layer "F.Cu")
		(at 414.655762 -87.159084 -90)
		(property "Reference" "U8E1"
			(at -3.99669 -0.20828 0)
			(unlocked yes)
			(layer "F.SilkS")
			(effects
				(font
					(size 0.7874 0.5842)
					(thickness 0.1524)
				)
				(justify left)
			)
		)
		(property "Value" ""
			(at 0 0 270)
			(layer "F.Fab")
			(effects
				(font
					(size 1.27 1.27)
				)
			)
		)
		(duplicate_pad_numbers_are_jumpers no)
		(fp_line
			(start -1.82499 1.82499)
			(end -1.82499 1.660144)
			(stroke
				(width 0.1524)
				(type default)
			)
			(layer "F.SilkS")
		)
		(fp_line
			(start -1.411732 1.82499)
			(end -1.82499 1.82499)
			(stroke
				(width 0.1524)
				(type default)
			)
			(layer "F.SilkS")
		)
		(fp_line
			(start 0.088392 1.82499)
			(end -0.089408 1.82499)
			(stroke
				(width 0.1524)
				(type default)
			)
			(layer "F.SilkS")
		)
		(fp_line
			(start 1.82499 1.82499)
			(end 1.410208 1.82499)
			(stroke
				(width 0.1524)
				(type default)
			)
			(layer "F.SilkS")
		)
		(fp_line
			(start 1.82499 1.660144)
			(end 1.82499 1.82499)
			(stroke
				(width 0.1524)
				(type default)
			)
			(layer "F.SilkS")
		)
		(fp_line
			(start -1.82499 -1.660906)
			(end -1.82499 -1.82499)
			(stroke
				(width 0.1524)
				(type default)
			)
			(layer "F.SilkS")
		)
		(fp_line
			(start -1.82499 -1.82499)
			(end -1.411732 -1.82499)
			(stroke
				(width 0.1524)
				(type default)
			)
			(layer "F.SilkS")
		)
		(fp_line
			(start -0.089408 -1.82499)
			(end 0.088392 -1.82499)
			(stroke
				(width 0.1524)
				(type default)
			)
			(layer "F.SilkS")
		)
		(fp_line
			(start 1.410208 -1.82499)
			(end 1.82499 -1.82499)
			(stroke
				(width 0.1524)
				(type default)
			)
			(layer "F.SilkS")
		)
		(fp_line
			(start 1.82499 -1.82499)
			(end 1.82499 -1.660906)
			(stroke
				(width 0.1524)
				(type default)
			)
			(layer "F.SilkS")
		)
		(fp_circle
			(center -1.17856 -2.466086)
			(end -1.17856 -2.593086)
			(stroke
				(width 0.254)
				(type default)
			)
			(fill no)
			(layer "F.SilkS")
		)
		(fp_poly
			(pts
				(xy -1.0287 1.0287) (xy -1.0287 -1.0287) (xy 1.0287 -1.0287) (xy 1.0287 1.0287)
			)
			(stroke
				(width 0)
				(type default)
			)
			(fill yes)
			(layer "F.Paste")
		)
		(fp_rect
			(start -1.82499 1.82499)
			(end 1.82499 -1.82499)
			(stroke
				(width 0)
				(type default)
			)
			(fill no)
			(layer "F.CrtYd")
		)
		(fp_line
			(start -1.82499 1.82499)
			(end -1.82499 -1.82499)
			(stroke
				(width 0.1)
				(type default)
			)
			(layer "F.Fab")
		)
		(fp_line
			(start 1.82499 1.82499)
			(end -1.82499 1.82499)
			(stroke
				(width 0.1)
				(type default)
			)
			(layer "F.Fab")
		)
		(fp_line
			(start -1.82499 -1.82499)
			(end 1.82499 -1.82499)
			(stroke
				(width 0.1)
				(type default)
			)
			(layer "F.Fab")
		)
		(fp_line
			(start 1.82499 -1.82499)
			(end 1.82499 1.82499)
			(stroke
				(width 0.1)
				(type default)
			)
			(layer "F.Fab")
		)
		(fp_circle
			(center -1.17856 -2.466086)
			(end -1.17856 -2.593086)
			(stroke
				(width 0.254)
				(type default)
			)
			(fill no)
			(layer "F.Fab")
		)
		(pad "1" smd rect
			(at -0.750062 -1.664208 270)
			(size 0.3048 0.762)
			(layers "F.Cu" "F.Mask" "F.Paste")
			(net "IRQ_FORCE_NM_THROTTLE_N")
		)
		(pad "2" smd rect
			(at -1.664208 -0.999998 270)
			(size 0.762 0.3048)
			(layers "F.Cu" "F.Mask" "F.Paste")
			(net "FM_OC_DETECT_N")
		)
		(pad "3" smd rect
			(at -1.664208 -0.500126 270)
			(size 0.762 0.3048)
			(layers "F.Cu" "F.Mask" "F.Paste")
			(net "FM_FAST_PROCHOT_AND_OUT_0_N")
		)
		(pad "4" smd rect
			(at -1.664208 0 270)
			(size 0.762 0.3048)
			(layers "F.Cu" "F.Mask" "F.Paste")
			(net "IRQ_UV_DETECT_N")
		)
		(pad "5" smd rect
			(at -1.664208 0.500126 270)
			(size 0.762 0.3048)
			(layers "F.Cu" "F.Mask" "F.Paste")
			(net "FM_HSC_TIMER_EXP_N")
		)
		(pad "6" smd rect
			(at -1.664208 0.999998 270)
			(size 0.762 0.3048)
			(layers "F.Cu" "F.Mask" "F.Paste")
			(net "FM_FAST_PROCHOT_AND_OUT_1_N")
		)
		(pad "7" smd rect
			(at -0.750062 1.664208 270)
			(size 0.3048 0.762)
			(layers "F.Cu" "F.Mask" "F.Paste")
			(net "GND")
		)
		(pad "8" smd rect
			(at 0.750062 1.664208 270)
			(size 0.3048 0.762)
			(layers "F.Cu" "F.Mask" "F.Paste")
			(net "FM_CTNR_PS_ON_R")
		)
		(pad "9" smd rect
			(at 1.664208 0.999998 270)
			(size 0.762 0.3048)
			(layers "F.Cu" "F.Mask" "F.Paste")
			(net "FM_PS_EN")
		)
		(pad "10" smd rect
			(at 1.664208 0.500126 270)
			(size 0.762 0.3048)
			(layers "F.Cu" "F.Mask" "F.Paste")
			(net "PWRGD_P12V_HSC_DLY")
		)
		(pad "11" smd rect
			(at 1.664208 0 270)
			(size 0.762 0.3048)
			(layers "F.Cu" "F.Mask" "F.Paste")
			(net "FM_FAST_PROCHOT_THROTTLE_IN_N")
		)
		(pad "12" smd rect
			(at 1.664208 -0.500126 270)
			(size 0.762 0.3048)
			(layers "F.Cu" "F.Mask" "F.Paste")
			(net "FM_FAST_PROCHOT_AND_OUT_0_N")
		)
		(pad "13" smd rect
			(at 1.664208 -0.999998 270)
			(size 0.762 0.3048)
			(layers "F.Cu" "F.Mask" "F.Paste")
			(net "FM_FAST_PROCHOT_AND_OUT_1_N")
		)
		(pad "14" smd rect
			(at 0.750062 -1.664208 270)
			(size 0.3048 0.762)
			(layers "F.Cu" "F.Mask" "F.Paste")
			(net "P3V3_STBY")
		)
		(pad "15" smd rect
			(at 0 0 270)
			(size 2.0574 2.0574)
			(layers "F.Cu" "F.Mask" "F.Paste")
			(net "GND")
		)
	)
	(footprint ""
		(layer "F.Cu")
		(at 333.726536 -20.801584 90)
		(property "Reference" "R7F33"
			(at 0 0 90)
			(layer "F.SilkS")
			(hide yes)
			(effects
				(font
					(size 1.27 1.27)
				)
			)
		)
		(property "Value" ""
			(at 0 0 90)
			(layer "F.Fab")
			(effects
				(font
					(size 1.27 1.27)
				)
			)
		)
		(duplicate_pad_numbers_are_jumpers no)
		(fp_rect
			(start 0.2794 0.9906)
			(end -0.2794 -0.1016)
			(stroke
				(width 0)
				(type default)
			)
			(fill no)
			(layer "F.CrtYd")
		)
		(fp_line
			(start 0.2794 -0.1016)
			(end -0.2794 -0.1016)
			(stroke
				(width 0.1)
				(type default)
			)
			(layer "F.Fab")
		)
		(fp_line
			(start -0.2794 -0.1016)
			(end -0.2794 0.9906)
			(stroke
				(width 0.1)
				(type default)
			)
			(layer "F.Fab")
		)
		(fp_line
			(start 0.2794 0.9906)
			(end 0.2794 -0.1016)
			(stroke
				(width 0.1)
				(type default)
			)
			(layer "F.Fab")
		)
		(fp_line
			(start -0.2794 0.9906)
			(end 0.2794 0.9906)
			(stroke
				(width 0.1)
				(type default)
			)
			(layer "F.Fab")
		)
		(pad "1" smd rect
			(at 0 0 90)
			(size 0.508 0.508)
			(layers "F.Cu" "F.Mask" "F.Paste")
			(net "P5V_STBY")
		)
		(pad "2" smd rect
			(at 0 0.889 90)
			(size 0.508 0.508)
			(layers "F.Cu" "F.Mask" "F.Paste")
			(net "FAN_PWM_OUT_SYS1_R")
		)
		(zone
			(layer "F.Cu")
			(hatch none 0.5)
			(connect_pads
				(clearance 0)
			)
			(min_thickness 0.25)
			(keepout
				(tracks allowed)
				(vias not_allowed)
				(pads allowed)
				(copperpour not_allowed)
				(footprints allowed)
			)
			(placement
				(enabled no)
				(sheetname "")
			)
			(fill
				(thermal_gap 0.5)
				(thermal_bridge_width 0.5)
				(island_removal_mode 0)
			)
			(polygon
				(pts
					(xy 334.361536 -21.055584) (xy 333.980536 -21.055584) (xy 333.980536 -20.547584) (xy 334.361536 -20.547584)
				)
			)
		)
		(zone
			(layer "F.Cu")
			(hatch none 0.5)
			(connect_pads
				(clearance 0)
			)
			(min_thickness 0.25)
			(keepout
				(tracks not_allowed)
				(vias allowed)
				(pads allowed)
				(copperpour not_allowed)
				(footprints allowed)
			)
			(placement
				(enabled no)
				(sheetname "")
			)
			(fill
				(thermal_gap 0.5)
				(thermal_bridge_width 0.5)
				(island_removal_mode 0)
			)
			(polygon
				(pts
					(xy 334.361536 -21.055584) (xy 333.980536 -21.055584) (xy 333.980536 -20.547584) (xy 334.361536 -20.547584)
				)
			)
		)
	)
	(footprint ""
		(layer "F.Cu")
		(at 419.1635 -57.1881)
		(property "Reference" "Q8E1"
			(at 2.1463 0.18669 0)
			(unlocked yes)
			(layer "F.SilkS")
			(effects
				(font
					(size 0.7874 0.5842)
					(thickness 0.1524)
				)
				(justify left)
			)
		)
		(property "Value" ""
			(at 0 0 0)
			(layer "F.Fab")
			(effects
				(font
					(size 1.27 1.27)
				)
			)
		)
		(duplicate_pad_numbers_are_jumpers no)
		(fp_line
			(start 0.381 0.635)
			(end 0.381 1.27)
			(stroke
				(width 0.1524)
				(type default)
			)
			(layer "F.SilkS")
		)
		(fp_line
			(start 0.9525 -0.5715)
			(end 1.778 -0.5715)
			(stroke
				(width 0.1524)
				(type default)
			)
			(layer "F.SilkS")
		)
		(fp_line
			(start 0.9525 2.4765)
			(end 1.778 2.4765)
			(stroke
				(width 0.1524)
				(type default)
			)
			(layer "F.SilkS")
		)
		(fp_line
			(start 1.778 -0.5715)
			(end 1.778 0.3175)
			(stroke
				(width 0.1524)
				(type default)
			)
			(layer "F.SilkS")
		)
		(fp_line
			(start 1.778 2.4765)
			(end 1.778 1.5875)
			(stroke
				(width 0.1524)
				(type default)
			)
			(layer "F.SilkS")
		)
		(fp_circle
			(center -0.636524 -0.804672)
			(end -0.509524 -0.804672)
			(stroke
				(width 0.254)
				(type default)
			)
			(fill no)
			(layer "F.SilkS")
		)
		(fp_poly
			(pts
				(xy 1.778 2.4765) (xy 0.381 2.4765) (xy 0.381 -0.5715) (xy 1.778 -0.5715)
			)
			(stroke
				(width 0)
				(type default)
			)
			(fill no)
			(layer "F.CrtYd")
		)
		(fp_line
			(start 0.381 -0.5715)
			(end 0.381 2.4765)
			(stroke
				(width 0.1)
				(type default)
			)
			(layer "F.Fab")
		)
		(fp_line
			(start 0.381 2.4765)
			(end 1.778 2.4765)
			(stroke
				(width 0.1)
				(type default)
			)
			(layer "F.Fab")
		)
		(fp_line
			(start 1.778 -0.5715)
			(end 0.381 -0.5715)
			(stroke
				(width 0.1)
				(type default)
			)
			(layer "F.Fab")
		)
		(fp_line
			(start 1.778 2.4765)
			(end 1.778 -0.5715)
			(stroke
				(width 0.1)
				(type default)
			)
			(layer "F.Fab")
		)
		(fp_circle
			(center -0.9525 -0.9271)
			(end -0.8255 -0.9271)
			(stroke
				(width 0.254)
				(type default)
			)
			(fill no)
			(layer "F.Fab")
		)
		(pad "1" smd rect
			(at 0 0)
			(size 1.143 0.508)
			(layers "F.Cu" "F.Mask" "F.Paste")
			(net "RST_PLTRST_N")
		)
		(pad "2" smd rect
			(at 0 1.905)
			(size 1.143 0.508)
			(layers "F.Cu" "F.Mask" "F.Paste")
			(net "GND")
		)
		(pad "3" smd rect
			(at 2.159 0.9525)
			(size 1.143 0.508)
			(layers "F.Cu" "F.Mask" "F.Paste")
			(net "RST_PLTRST_TOP_SWAP")
		)
	)
	(footprint ""
		(layer "F.Cu")
		(at 419.862 -21.6535)
		(property "Reference" "R2T49"
			(at 0 0 0)
			(layer "F.SilkS")
			(hide yes)
			(effects
				(font
					(size 1.27 1.27)
				)
			)
		)
		(property "Value" ""
			(at 0 0 0)
			(layer "F.Fab")
			(effects
				(font
					(size 1.27 1.27)
				)
			)
		)
		(duplicate_pad_numbers_are_jumpers no)
		(fp_poly
			(pts
				(xy -0.2794 -0.1016) (xy 0.2794 -0.1016) (xy 0.2794 0.9906) (xy -0.2794 0.9906)
			)
			(stroke
				(width 0)
				(type default)
			)
			(fill no)
			(layer "F.CrtYd")
		)
		(fp_line
			(start -0.2794 -0.1016)
			(end -0.2794 0.9906)
			(stroke
				(width 0.1)
				(type default)
			)
			(layer "F.Fab")
		)
		(fp_line
			(start -0.2794 0.9906)
			(end 0.2794 0.9906)
			(stroke
				(width 0.1)
				(type default)
			)
			(layer "F.Fab")
		)
		(fp_line
			(start 0.2794 -0.1016)
			(end -0.2794 -0.1016)
			(stroke
				(width 0.1)
				(type default)
			)
			(layer "F.Fab")
		)
		(fp_line
			(start 0.2794 0.9906)
			(end 0.2794 -0.1016)
			(stroke
				(width 0.1)
				(type default)
			)
			(layer "F.Fab")
		)
		(pad "1" smd rect
			(at 0 0)
			(size 0.508 0.508)
			(layers "F.Cu" "F.Mask" "F.Paste")
			(net "SMB_BMC_PMBUS_STBY_LVC3_SDA_R")
		)
		(pad "2" smd rect
			(at 0 0.889)
			(size 0.508 0.508)
			(layers "F.Cu" "F.Mask" "F.Paste")
			(net "SMB_BMC_PMBUS_STBY_LVC3_SDA")
		)
		(zone
			(layer "F.Cu")
			(hatch none 0.5)
			(connect_pads
				(clearance 0)
			)
			(min_thickness 0.25)
			(keepout
				(tracks allowed)
				(vias not_allowed)
				(pads allowed)
				(copperpour not_allowed)
				(footprints allowed)
			)
			(placement
				(enabled no)
				(sheetname "")
			)
			(fill
				(thermal_gap 0.5)
				(thermal_bridge_width 0.5)
				(island_removal_mode 0)
			)
			(polygon
				(pts
					(xy 419.608 -21.3995) (xy 420.116 -21.3995) (xy 420.116 -21.0185) (xy 419.608 -21.0185)
				)
			)
		)
		(zone
			(layer "F.Cu")
			(hatch none 0.5)
			(connect_pads
				(clearance 0)
			)
			(min_thickness 0.25)
			(keepout
				(tracks not_allowed)
				(vias allowed)
				(pads allowed)
				(copperpour not_allowed)
				(footprints allowed)
			)
			(placement
				(enabled no)
				(sheetname "")
			)
			(fill
				(thermal_gap 0.5)
				(thermal_bridge_width 0.5)
				(island_removal_mode 0)
			)
			(polygon
				(pts
					(xy 419.608 -21.0185) (xy 420.116 -21.0185) (xy 420.116 -21.3995) (xy 419.608 -21.3995)
				)
			)
		)
	)
	(footprint ""
		(layer "F.Cu")
		(at 98.18624 -73.318116)
		(property "Reference" "C2D34"
			(at 0 0 0)
			(layer "F.SilkS")
			(hide yes)
			(effects
				(font
					(size 1.27 1.27)
				)
			)
		)
		(property "Value" ""
			(at 0 0 0)
			(layer "F.Fab")
			(effects
				(font
					(size 1.27 1.27)
				)
			)
		)
		(duplicate_pad_numbers_are_jumpers no)
		(fp_poly
			(pts
				(xy -0.4953 -0.2032) (xy 0.4953 -0.2032) (xy 0.4953 1.6002) (xy -0.4953 1.6002)
			)
			(stroke
				(width 0)
				(type default)
			)
			(fill no)
			(layer "F.CrtYd")
		)
		(fp_line
			(start -0.4953 -0.2032)
			(end 0.4953 -0.2032)
			(stroke
				(width 0.1)
				(type default)
			)
			(layer "F.Fab")
		)
		(fp_line
			(start -0.4953 1.6002)
			(end -0.4953 -0.2032)
			(stroke
				(width 0.1)
				(type default)
			)
			(layer "F.Fab")
		)
		(fp_line
			(start 0.4953 -0.2032)
			(end 0.4953 1.6002)
			(stroke
				(width 0.1)
				(type default)
			)
			(layer "F.Fab")
		)
		(fp_line
			(start 0.4953 1.6002)
			(end -0.4953 1.6002)
			(stroke
				(width 0.1)
				(type default)
			)
			(layer "F.Fab")
		)
		(pad "1" smd rect
			(at 0 0)
			(size 0.762 0.889)
			(layers "F.Cu" "F.Mask" "F.Paste")
			(net "PVCCIN_CPU1")
		)
		(pad "2" smd rect
			(at 0 1.397)
			(size 0.762 0.889)
			(layers "F.Cu" "F.Mask" "F.Paste")
			(net "GND")
		)
		(zone
			(layer "F.Cu")
			(hatch none 0.5)
			(connect_pads
				(clearance 0)
			)
			(min_thickness 0.25)
			(keepout
				(tracks not_allowed)
				(vias allowed)
				(pads allowed)
				(copperpour not_allowed)
				(footprints allowed)
			)
			(placement
				(enabled no)
				(sheetname "")
			)
			(fill
				(thermal_gap 0.5)
				(thermal_bridge_width 0.5)
				(island_removal_mode 0)
			)
			(polygon
				(pts
					(xy 97.80524 -72.873616) (xy 98.56724 -72.873616) (xy 98.56724 -72.365616) (xy 97.80524 -72.365616)
				)
			)
		)
	)
	(footprint ""
		(layer "F.Cu")
		(at 21.6408 -87.3506 -90)
		(property "Reference" "R1D4"
			(at 0 0 270)
			(layer "F.SilkS")
			(hide yes)
			(effects
				(font
					(size 1.27 1.27)
				)
			)
		)
		(property "Value" ""
			(at 0 0 270)
			(layer "F.Fab")
			(effects
				(font
					(size 1.27 1.27)
				)
			)
		)
		(duplicate_pad_numbers_are_jumpers no)
		(fp_rect
			(start 0.2794 0.9906)
			(end -0.2794 -0.1016)
			(stroke
				(width 0)
				(type default)
			)
			(fill no)
			(layer "F.CrtYd")
		)
		(fp_line
			(start -0.2794 0.9906)
			(end 0.2794 0.9906)
			(stroke
				(width 0.1)
				(type default)
			)
			(layer "F.Fab")
		)
		(fp_line
			(start 0.2794 0.9906)
			(end 0.2794 -0.1016)
			(stroke
				(width 0.1)
				(type default)
			)
			(layer "F.Fab")
		)
		(fp_line
			(start -0.2794 -0.1016)
			(end -0.2794 0.9906)
			(stroke
				(width 0.1)
				(type default)
			)
			(layer "F.Fab")
		)
		(fp_line
			(start 0.2794 -0.1016)
			(end -0.2794 -0.1016)
			(stroke
				(width 0.1)
				(type default)
			)
			(layer "F.Fab")
		)
		(pad "1" smd rect
			(at 0 0 270)
			(size 0.508 0.508)
			(layers "F.Cu" "F.Mask" "F.Paste")
			(net "VSENSE_PVCCIN_CPU1_P")
		)
		(pad "2" smd rect
			(at 0 0.889 270)
			(size 0.508 0.508)
			(layers "F.Cu" "F.Mask" "F.Paste")
			(net "VSENSE_PVCCIN_CPU1_AVSP")
		)
		(zone
			(layer "F.Cu")
			(hatch none 0.5)
			(connect_pads
				(clearance 0)
			)
			(min_thickness 0.25)
			(keepout
				(tracks not_allowed)
				(vias allowed)
				(pads allowed)
				(copperpour not_allowed)
				(footprints allowed)
			)
			(placement
				(enabled no)
				(sheetname "")
			)
			(fill
				(thermal_gap 0.5)
				(thermal_bridge_width 0.5)
				(island_removal_mode 0)
			)
			(polygon
				(pts
					(xy 21.0058 -87.0966) (xy 21.3868 -87.0966) (xy 21.3868 -87.6046) (xy 21.0058 -87.6046)
				)
			)
		)
		(zone
			(layer "F.Cu")
			(hatch none 0.5)
			(connect_pads
				(clearance 0)
			)
			(min_thickness 0.25)
			(keepout
				(tracks allowed)
				(vias not_allowed)
				(pads allowed)
				(copperpour not_allowed)
				(footprints allowed)
			)
			(placement
				(enabled no)
				(sheetname "")
			)
			(fill
				(thermal_gap 0.5)
				(thermal_bridge_width 0.5)
				(island_removal_mode 0)
			)
			(polygon
				(pts
					(xy 21.0058 -87.0966) (xy 21.3868 -87.0966) (xy 21.3868 -87.6046) (xy 21.0058 -87.6046)
				)
			)
		)
	)
)
